(kicad_pcb
	(version 20260206)
	(generator "pcbnew")
	(generator_version "10.0")
	(general
		(thickness 1.6)
		(legacy_teardrops no)
	)
	(paper "A4")
	(title_block
		(title "12092022_DA0F0TMDCD0_F0T_Management_Board_D_brd_V3_OCP.brd")
		(comment 1 "Grand Teton / footprints 300-305 of 1440")
	)
	(layers
		(0 "F.Cu" signal "TOP")
		(4 "In1.Cu" signal "GND")
		(6 "In2.Cu" signal "IN1")
		(8 "In3.Cu" signal "GND1")
		(10 "In4.Cu" signal "IN2")
		(12 "In5.Cu" signal "VCC")
		(14 "In6.Cu" signal "VCC1")
		(16 "In7.Cu" signal "IN3")
		(18 "In8.Cu" signal "GND2")
		(20 "In9.Cu" signal "IN4")
		(22 "In10.Cu" signal "GND3")
		(2 "B.Cu" signal "BOTTOM")
		(9 "F.Adhes" user "F.Adhesive")
		(11 "B.Adhes" user "B.Adhesive")
		(13 "F.Paste" user "Package Geometry/Pastemask Top")
		(15 "B.Paste" user "Package Geometry/Pastemask Bottom")
		(5 "F.SilkS" user "Ref Des/Silkscreen Top")
		(7 "B.SilkS" user "Ref Des/Silkscreen Bottom")
		(1 "F.Mask" user "Board Geometry/Soldermask Top")
		(3 "B.Mask" user "Board Geometry/Soldermask Bottom")
		(17 "Dwgs.User" user "User.Drawings")
		(19 "Cmts.User" user "User.Comments")
		(21 "Eco1.User" user "User.Eco1")
		(23 "Eco2.User" user "User.Eco2")
		(25 "Edge.Cuts" user "Board Geometry/Outline")
		(27 "Margin" user)
		(31 "F.CrtYd" user "Package Geometry/Place Bound Top")
		(29 "B.CrtYd" user "Package Geometry/Place Bound Bottom")
		(35 "F.Fab" user "Ref Des/Assembly Top")
		(33 "B.Fab" user "Ref Des/Assembly Bottom")
	)
	(footprint ""
		(layer "F.Cu")
		(at 24.892 -83.7438 90)
		(property "Reference" "R123"
			(at 0 0 90)
			(layer "F.SilkS")
			(hide yes)
			(effects
				(font
					(size 1.27 1.27)
				)
			)
		)
		(property "Value" ""
			(at 0 0 90)
			(layer "F.Fab")
			(effects
				(font
					(size 1.27 1.27)
				)
			)
		)
		(duplicate_pad_numbers_are_jumpers no)
		(fp_line
			(start 0.7874 -0.4064)
			(end 0.7874 0.4064)
			(stroke
				(width 0.1524)
				(type default)
			)
			(layer "F.SilkS")
		)
		(fp_line
			(start -0.7874 -0.4064)
			(end 0.7874 -0.4064)
			(stroke
				(width 0.1524)
				(type default)
			)
			(layer "F.SilkS")
		)
		(fp_line
			(start 0.7874 0.4064)
			(end -0.7874 0.4064)
			(stroke
				(width 0.1524)
				(type default)
			)
			(layer "F.SilkS")
		)
		(fp_line
			(start -0.7874 0.4064)
			(end -0.7874 -0.4064)
			(stroke
				(width 0.1524)
				(type default)
			)
			(layer "F.SilkS")
		)
		(fp_line
			(start -0.12065 -0.305054)
			(end -0.12065 -0.2794)
			(stroke
				(width 0.1)
				(type default)
			)
			(layer "F.Fab")
		)
		(fp_line
			(start -0.67945 -0.305054)
			(end -0.12065 -0.305054)
			(stroke
				(width 0.1)
				(type default)
			)
			(layer "F.Fab")
		)
		(fp_line
			(start 0.67945 -0.3048)
			(end 0.67945 0.3048)
			(stroke
				(width 0.1)
				(type default)
			)
			(layer "F.Fab")
		)
		(fp_line
			(start 0.12065 -0.3048)
			(end 0.67945 -0.3048)
			(stroke
				(width 0.1)
				(type default)
			)
			(layer "F.Fab")
		)
		(fp_line
			(start 0.12065 -0.2794)
			(end 0.12065 -0.3048)
			(stroke
				(width 0.1)
				(type default)
			)
			(layer "F.Fab")
		)
		(fp_line
			(start -0.12065 -0.2794)
			(end 0.12065 -0.2794)
			(stroke
				(width 0.1)
				(type default)
			)
			(layer "F.Fab")
		)
		(fp_line
			(start 0.120396 0.2794)
			(end -0.12065 0.2794)
			(stroke
				(width 0.1)
				(type default)
			)
			(layer "F.Fab")
		)
		(fp_line
			(start -0.12065 0.2794)
			(end -0.12065 0.3048)
			(stroke
				(width 0.1)
				(type default)
			)
			(layer "F.Fab")
		)
		(fp_line
			(start 0.67945 0.3048)
			(end 0.120396 0.3048)
			(stroke
				(width 0.1)
				(type default)
			)
			(layer "F.Fab")
		)
		(fp_line
			(start 0.120396 0.3048)
			(end 0.120396 0.2794)
			(stroke
				(width 0.1)
				(type default)
			)
			(layer "F.Fab")
		)
		(fp_line
			(start -0.12065 0.3048)
			(end -0.67945 0.3048)
			(stroke
				(width 0.1)
				(type default)
			)
			(layer "F.Fab")
		)
		(fp_line
			(start -0.67945 0.3048)
			(end -0.67945 -0.305054)
			(stroke
				(width 0.1)
				(type default)
			)
			(layer "F.Fab")
		)
		(pad "1" smd circle
			(at -0.40005 0 90)
			(size 0 0)
			(layers "F.Cu" "F.Mask" "F.Paste")
			(net "FM_TPM_PRSNT_1_N")
		)
		(pad "2" smd circle
			(at 0.40005 0 90)
			(size 0 0)
			(layers "F.Cu" "F.Mask" "F.Paste")
			(net "FM_TPM_PRSNT_1_R_N")
		)
	)
	(footprint ""
		(layer "F.Cu")
		(at 68.189094 -97.877122)
		(property "Reference" "R500"
			(at 0 0 0)
			(layer "F.SilkS")
			(hide yes)
			(effects
				(font
					(size 1.27 1.27)
				)
			)
		)
		(property "Value" ""
			(at 0 0 0)
			(layer "F.Fab")
			(effects
				(font
					(size 1.27 1.27)
				)
			)
		)
		(duplicate_pad_numbers_are_jumpers no)
		(fp_line
			(start -0.7874 -0.4064)
			(end 0.7874 -0.4064)
			(stroke
				(width 0.1524)
				(type default)
			)
			(layer "F.SilkS")
		)
		(fp_line
			(start -0.7874 0.4064)
			(end -0.7874 -0.4064)
			(stroke
				(width 0.1524)
				(type default)
			)
			(layer "F.SilkS")
		)
		(fp_line
			(start 0.7874 -0.4064)
			(end 0.7874 0.4064)
			(stroke
				(width 0.1524)
				(type default)
			)
			(layer "F.SilkS")
		)
		(fp_line
			(start 0.7874 0.4064)
			(end -0.7874 0.4064)
			(stroke
				(width 0.1524)
				(type default)
			)
			(layer "F.SilkS")
		)
		(fp_line
			(start -0.67945 -0.305054)
			(end -0.12065 -0.305054)
			(stroke
				(width 0.1)
				(type default)
			)
			(layer "F.Fab")
		)
		(fp_line
			(start -0.67945 0.3048)
			(end -0.67945 -0.305054)
			(stroke
				(width 0.1)
				(type default)
			)
			(layer "F.Fab")
		)
		(fp_line
			(start -0.12065 -0.305054)
			(end -0.12065 -0.2794)
			(stroke
				(width 0.1)
				(type default)
			)
			(layer "F.Fab")
		)
		(fp_line
			(start -0.12065 -0.2794)
			(end 0.12065 -0.2794)
			(stroke
				(width 0.1)
				(type default)
			)
			(layer "F.Fab")
		)
		(fp_line
			(start -0.12065 0.2794)
			(end -0.12065 0.3048)
			(stroke
				(width 0.1)
				(type default)
			)
			(layer "F.Fab")
		)
		(fp_line
			(start -0.12065 0.3048)
			(end -0.67945 0.3048)
			(stroke
				(width 0.1)
				(type default)
			)
			(layer "F.Fab")
		)
		(fp_line
			(start 0.120396 0.2794)
			(end -0.12065 0.2794)
			(stroke
				(width 0.1)
				(type default)
			)
			(layer "F.Fab")
		)
		(fp_line
			(start 0.120396 0.3048)
			(end 0.120396 0.2794)
			(stroke
				(width 0.1)
				(type default)
			)
			(layer "F.Fab")
		)
		(fp_line
			(start 0.12065 -0.3048)
			(end 0.67945 -0.3048)
			(stroke
				(width 0.1)
				(type default)
			)
			(layer "F.Fab")
		)
		(fp_line
			(start 0.12065 -0.2794)
			(end 0.12065 -0.3048)
			(stroke
				(width 0.1)
				(type default)
			)
			(layer "F.Fab")
		)
		(fp_line
			(start 0.67945 -0.3048)
			(end 0.67945 0.3048)
			(stroke
				(width 0.1)
				(type default)
			)
			(layer "F.Fab")
		)
		(fp_line
			(start 0.67945 0.3048)
			(end 0.120396 0.3048)
			(stroke
				(width 0.1)
				(type default)
			)
			(layer "F.Fab")
		)
		(pad "1" smd circle
			(at -0.40005 0)
			(size 0 0)
			(layers "F.Cu" "F.Mask" "F.Paste")
			(net "SPI_TPM_CS_N_R")
		)
		(pad "2" smd circle
			(at 0.40005 0)
			(size 0 0)
			(layers "F.Cu" "F.Mask" "F.Paste")
			(net "SPI_TPM_CS_R_N")
		)
	)
	(footprint ""
		(layer "F.Cu")
		(at 47.567088 -20.435062 90)
		(property "Reference" "C179"
			(at 0 0 90)
			(layer "F.SilkS")
			(hide yes)
			(effects
				(font
					(size 1.27 1.27)
				)
			)
		)
		(property "Value" ""
			(at 0 0 90)
			(layer "F.Fab")
			(effects
				(font
					(size 1.27 1.27)
				)
			)
		)
		(duplicate_pad_numbers_are_jumpers no)
		(fp_line
			(start 0.7874 -0.4064)
			(end 0.7874 0.4064)
			(stroke
				(width 0.1524)
				(type default)
			)
			(layer "F.SilkS")
		)
		(fp_line
			(start -0.7874 -0.4064)
			(end 0.7874 -0.4064)
			(stroke
				(width 0.1524)
				(type default)
			)
			(layer "F.SilkS")
		)
		(fp_line
			(start 0.7874 0.4064)
			(end -0.7874 0.4064)
			(stroke
				(width 0.1524)
				(type default)
			)
			(layer "F.SilkS")
		)
		(fp_line
			(start -0.7874 0.4064)
			(end -0.7874 -0.4064)
			(stroke
				(width 0.1524)
				(type default)
			)
			(layer "F.SilkS")
		)
		(fp_line
			(start -0.12065 -0.305054)
			(end -0.12065 -0.2794)
			(stroke
				(width 0.1)
				(type default)
			)
			(layer "F.Fab")
		)
		(fp_line
			(start -0.67945 -0.305054)
			(end -0.12065 -0.305054)
			(stroke
				(width 0.1)
				(type default)
			)
			(layer "F.Fab")
		)
		(fp_line
			(start 0.67945 -0.3048)
			(end 0.67945 0.3048)
			(stroke
				(width 0.1)
				(type default)
			)
			(layer "F.Fab")
		)
		(fp_line
			(start 0.12065 -0.3048)
			(end 0.67945 -0.3048)
			(stroke
				(width 0.1)
				(type default)
			)
			(layer "F.Fab")
		)
		(fp_line
			(start 0.12065 -0.2794)
			(end 0.12065 -0.3048)
			(stroke
				(width 0.1)
				(type default)
			)
			(layer "F.Fab")
		)
		(fp_line
			(start -0.12065 -0.2794)
			(end 0.12065 -0.2794)
			(stroke
				(width 0.1)
				(type default)
			)
			(layer "F.Fab")
		)
		(fp_line
			(start 0.120396 0.2794)
			(end -0.12065 0.2794)
			(stroke
				(width 0.1)
				(type default)
			)
			(layer "F.Fab")
		)
		(fp_line
			(start -0.12065 0.2794)
			(end -0.12065 0.3048)
			(stroke
				(width 0.1)
				(type default)
			)
			(layer "F.Fab")
		)
		(fp_line
			(start 0.67945 0.3048)
			(end 0.120396 0.3048)
			(stroke
				(width 0.1)
				(type default)
			)
			(layer "F.Fab")
		)
		(fp_line
			(start 0.120396 0.3048)
			(end 0.120396 0.2794)
			(stroke
				(width 0.1)
				(type default)
			)
			(layer "F.Fab")
		)
		(fp_line
			(start -0.12065 0.3048)
			(end -0.67945 0.3048)
			(stroke
				(width 0.1)
				(type default)
			)
			(layer "F.Fab")
		)
		(fp_line
			(start -0.67945 0.3048)
			(end -0.67945 -0.305054)
			(stroke
				(width 0.1)
				(type default)
			)
			(layer "F.Fab")
		)
		(pad "1" smd circle
			(at -0.40005 0 90)
			(size 0 0)
			(layers "F.Cu" "F.Mask" "F.Paste")
			(net "P5V_USB_REAR")
		)
		(pad "2" smd circle
			(at 0.40005 0 90)
			(size 0 0)
			(layers "F.Cu" "F.Mask" "F.Paste")
			(net "GND")
		)
	)
	(footprint ""
		(layer "F.Cu")
		(at 67.818 -106.2736 -90)
		(property "Reference" "R824"
			(at 0 0 270)
			(layer "F.SilkS")
			(hide yes)
			(effects
				(font
					(size 1.27 1.27)
				)
			)
		)
		(property "Value" ""
			(at 0 0 270)
			(layer "F.Fab")
			(effects
				(font
					(size 1.27 1.27)
				)
			)
		)
		(duplicate_pad_numbers_are_jumpers no)
		(fp_line
			(start -0.7874 0.4064)
			(end -0.7874 -0.4064)
			(stroke
				(width 0.1524)
				(type default)
			)
			(layer "F.SilkS")
		)
		(fp_line
			(start 0.7874 0.4064)
			(end -0.7874 0.4064)
			(stroke
				(width 0.1524)
				(type default)
			)
			(layer "F.SilkS")
		)
		(fp_line
			(start -0.7874 -0.4064)
			(end 0.7874 -0.4064)
			(stroke
				(width 0.1524)
				(type default)
			)
			(layer "F.SilkS")
		)
		(fp_line
			(start 0.7874 -0.4064)
			(end 0.7874 0.4064)
			(stroke
				(width 0.1524)
				(type default)
			)
			(layer "F.SilkS")
		)
		(fp_line
			(start -0.67945 0.3048)
			(end -0.67945 -0.305054)
			(stroke
				(width 0.1)
				(type default)
			)
			(layer "F.Fab")
		)
		(fp_line
			(start -0.12065 0.3048)
			(end -0.67945 0.3048)
			(stroke
				(width 0.1)
				(type default)
			)
			(layer "F.Fab")
		)
		(fp_line
			(start 0.120396 0.3048)
			(end 0.120396 0.2794)
			(stroke
				(width 0.1)
				(type default)
			)
			(layer "F.Fab")
		)
		(fp_line
			(start 0.67945 0.3048)
			(end 0.120396 0.3048)
			(stroke
				(width 0.1)
				(type default)
			)
			(layer "F.Fab")
		)
		(fp_line
			(start -0.12065 0.2794)
			(end -0.12065 0.3048)
			(stroke
				(width 0.1)
				(type default)
			)
			(layer "F.Fab")
		)
		(fp_line
			(start 0.120396 0.2794)
			(end -0.12065 0.2794)
			(stroke
				(width 0.1)
				(type default)
			)
			(layer "F.Fab")
		)
		(fp_line
			(start -0.12065 -0.2794)
			(end 0.12065 -0.2794)
			(stroke
				(width 0.1)
				(type default)
			)
			(layer "F.Fab")
		)
		(fp_line
			(start 0.12065 -0.2794)
			(end 0.12065 -0.3048)
			(stroke
				(width 0.1)
				(type default)
			)
			(layer "F.Fab")
		)
		(fp_line
			(start 0.12065 -0.3048)
			(end 0.67945 -0.3048)
			(stroke
				(width 0.1)
				(type default)
			)
			(layer "F.Fab")
		)
		(fp_line
			(start 0.67945 -0.3048)
			(end 0.67945 0.3048)
			(stroke
				(width 0.1)
				(type default)
			)
			(layer "F.Fab")
		)
		(fp_line
			(start -0.67945 -0.305054)
			(end -0.12065 -0.305054)
			(stroke
				(width 0.1)
				(type default)
			)
			(layer "F.Fab")
		)
		(fp_line
			(start -0.12065 -0.305054)
			(end -0.12065 -0.2794)
			(stroke
				(width 0.1)
				(type default)
			)
			(layer "F.Fab")
		)
		(pad "1" smd circle
			(at -0.40005 0 270)
			(size 0 0)
			(layers "F.Cu" "F.Mask" "F.Paste")
			(net "FM_VIRTUAL_RESEAT")
		)
		(pad "2" smd circle
			(at 0.40005 0 270)
			(size 0 0)
			(layers "F.Cu" "F.Mask" "F.Paste")
			(net "FM_VIRTUAL_RESEAT_BMC")
		)
	)
	(footprint ""
		(layer "F.Cu")
		(at 60.7314 -64.0588 90)
		(property "Reference" "R174"
			(at 0 0 90)
			(layer "F.SilkS")
			(hide yes)
			(effects
				(font
					(size 1.27 1.27)
				)
			)
		)
		(property "Value" ""
			(at 0 0 90)
			(layer "F.Fab")
			(effects
				(font
					(size 1.27 1.27)
				)
			)
		)
		(duplicate_pad_numbers_are_jumpers no)
		(fp_line
			(start 0.7874 -0.4064)
			(end 0.7874 0.4064)
			(stroke
				(width 0.1524)
				(type default)
			)
			(layer "F.SilkS")
		)
		(fp_line
			(start -0.7874 -0.4064)
			(end 0.7874 -0.4064)
			(stroke
				(width 0.1524)
				(type default)
			)
			(layer "F.SilkS")
		)
		(fp_line
			(start 0.7874 0.4064)
			(end -0.7874 0.4064)
			(stroke
				(width 0.1524)
				(type default)
			)
			(layer "F.SilkS")
		)
		(fp_line
			(start -0.7874 0.4064)
			(end -0.7874 -0.4064)
			(stroke
				(width 0.1524)
				(type default)
			)
			(layer "F.SilkS")
		)
		(fp_line
			(start -0.12065 -0.305054)
			(end -0.12065 -0.2794)
			(stroke
				(width 0.1)
				(type default)
			)
			(layer "F.Fab")
		)
		(fp_line
			(start -0.67945 -0.305054)
			(end -0.12065 -0.305054)
			(stroke
				(width 0.1)
				(type default)
			)
			(layer "F.Fab")
		)
		(fp_line
			(start 0.67945 -0.3048)
			(end 0.67945 0.3048)
			(stroke
				(width 0.1)
				(type default)
			)
			(layer "F.Fab")
		)
		(fp_line
			(start 0.12065 -0.3048)
			(end 0.67945 -0.3048)
			(stroke
				(width 0.1)
				(type default)
			)
			(layer "F.Fab")
		)
		(fp_line
			(start 0.12065 -0.2794)
			(end 0.12065 -0.3048)
			(stroke
				(width 0.1)
				(type default)
			)
			(layer "F.Fab")
		)
		(fp_line
			(start -0.12065 -0.2794)
			(end 0.12065 -0.2794)
			(stroke
				(width 0.1)
				(type default)
			)
			(layer "F.Fab")
		)
		(fp_line
			(start 0.120396 0.2794)
			(end -0.12065 0.2794)
			(stroke
				(width 0.1)
				(type default)
			)
			(layer "F.Fab")
		)
		(fp_line
			(start -0.12065 0.2794)
			(end -0.12065 0.3048)
			(stroke
				(width 0.1)
				(type default)
			)
			(layer "F.Fab")
		)
		(fp_line
			(start 0.67945 0.3048)
			(end 0.120396 0.3048)
			(stroke
				(width 0.1)
				(type default)
			)
			(layer "F.Fab")
		)
		(fp_line
			(start 0.120396 0.3048)
			(end 0.120396 0.2794)
			(stroke
				(width 0.1)
				(type default)
			)
			(layer "F.Fab")
		)
		(fp_line
			(start -0.12065 0.3048)
			(end -0.67945 0.3048)
			(stroke
				(width 0.1)
				(type default)
			)
			(layer "F.Fab")
		)
		(fp_line
			(start -0.67945 0.3048)
			(end -0.67945 -0.305054)
			(stroke
				(width 0.1)
				(type default)
			)
			(layer "F.Fab")
		)
		(pad "1" smd circle
			(at -0.40005 0 90)
			(size 0 0)
			(layers "F.Cu" "F.Mask" "F.Paste")
			(net "SPI_BMC_BIOS_ROM_CLK")
		)
		(pad "2" smd circle
			(at 0.40005 0 90)
			(size 0 0)
			(layers "F.Cu" "F.Mask" "F.Paste")
			(net "SPI_BMC_BIOS_ROM_R_CLK")
		)
	)
	(footprint ""
		(layer "F.Cu")
		(at 40.41648 -30.63748 -90)
		(property "Reference" "C38"
			(at 0 0 270)
			(layer "F.SilkS")
			(hide yes)
			(effects
				(font
					(size 1.27 1.27)
				)
			)
		)
		(property "Value" ""
			(at 0 0 270)
			(layer "F.Fab")
			(effects
				(font
					(size 1.27 1.27)
				)
			)
		)
		(duplicate_pad_numbers_are_jumpers no)
		(fp_line
			(start -0.7874 0.4064)
			(end -0.7874 -0.4064)
			(stroke
				(width 0.1524)
				(type default)
			)
			(layer "F.SilkS")
		)
		(fp_line
			(start 0.7874 0.4064)
			(end -0.7874 0.4064)
			(stroke
				(width 0.1524)
				(type default)
			)
			(layer "F.SilkS")
		)
		(fp_line
			(start -0.7874 -0.4064)
			(end 0.7874 -0.4064)
			(stroke
				(width 0.1524)
				(type default)
			)
			(layer "F.SilkS")
		)
		(fp_line
			(start 0.7874 -0.4064)
			(end 0.7874 0.4064)
			(stroke
				(width 0.1524)
				(type default)
			)
			(layer "F.SilkS")
		)
		(fp_line
			(start -0.67945 0.3048)
			(end -0.67945 -0.305054)
			(stroke
				(width 0.1)
				(type default)
			)
			(layer "F.Fab")
		)
		(fp_line
			(start -0.12065 0.3048)
			(end -0.67945 0.3048)
			(stroke
				(width 0.1)
				(type default)
			)
			(layer "F.Fab")
		)
		(fp_line
			(start 0.120396 0.3048)
			(end 0.120396 0.2794)
			(stroke
				(width 0.1)
				(type default)
			)
			(layer "F.Fab")
		)
		(fp_line
			(start 0.67945 0.3048)
			(end 0.120396 0.3048)
			(stroke
				(width 0.1)
				(type default)
			)
			(layer "F.Fab")
		)
		(fp_line
			(start -0.12065 0.2794)
			(end -0.12065 0.3048)
			(stroke
				(width 0.1)
				(type default)
			)
			(layer "F.Fab")
		)
		(fp_line
			(start 0.120396 0.2794)
			(end -0.12065 0.2794)
			(stroke
				(width 0.1)
				(type default)
			)
			(layer "F.Fab")
		)
		(fp_line
			(start -0.12065 -0.2794)
			(end 0.12065 -0.2794)
			(stroke
				(width 0.1)
				(type default)
			)
			(layer "F.Fab")
		)
		(fp_line
			(start 0.12065 -0.2794)
			(end 0.12065 -0.3048)
			(stroke
				(width 0.1)
				(type default)
			)
			(layer "F.Fab")
		)
		(fp_line
			(start 0.12065 -0.3048)
			(end 0.67945 -0.3048)
			(stroke
				(width 0.1)
				(type default)
			)
			(layer "F.Fab")
		)
		(fp_line
			(start 0.67945 -0.3048)
			(end 0.67945 0.3048)
			(stroke
				(width 0.1)
				(type default)
			)
			(layer "F.Fab")
		)
		(fp_line
			(start -0.67945 -0.305054)
			(end -0.12065 -0.305054)
			(stroke
				(width 0.1)
				(type default)
			)
			(layer "F.Fab")
		)
		(fp_line
			(start -0.12065 -0.305054)
			(end -0.12065 -0.2794)
			(stroke
				(width 0.1)
				(type default)
			)
			(layer "F.Fab")
		)
		(pad "1" smd circle
			(at -0.40005 0 270)
			(size 0 0)
			(layers "F.Cu" "F.Mask" "F.Paste")
			(net "P3V3_P1V8_SD2VDD")
		)
		(pad "2" smd circle
			(at 0.40005 0 270)
			(size 0 0)
			(layers "F.Cu" "F.Mask" "F.Paste")
			(net "GND")
		)
	)
)
